# T6G (Grand Teton) — schematic netlist excerpt (pin names and nets, part order shuffled) for the footprints in the layout excerpt that follows; sources: Cadence DE-HDL packaged netlist, KiCad conversion of 04192023_DAF0TMB3IC0_F0TG_MB_C_brd_V02_OCP.brd

R932  Q_RES  0 5% CHIP  pkg 0402LF  page 54 : A = CPU1_XTRIG_L7 ; B = CPU1_XTRIG_R1_L7
C2286  Q_CAP  22UF 4V 20% X6S  pkg C0402  page 72 : A = PVDDCR_SOC_P1 ; B = GND

(kicad_pcb
	(version 20260206)
	(generator "pcbnew")
	(generator_version "10.0")
	(general
		(thickness 1.6)
		(legacy_teardrops no)
	)
	(paper "A4")
	(title_block
		(title "04192023_DAF0TMB3IC0_F0TG_MB_C_brd_V02_OCP.brd")
		(comment 1 "Grand Teton / footprints 4720-4722 of 8354")
	)
	(layers
		(0 "F.Cu" signal "TOP")
		(4 "In1.Cu" signal "GND")
		(6 "In2.Cu" signal "IN1")
		(8 "In3.Cu" signal "GND1")
		(10 "In4.Cu" signal "IN2")
		(12 "In5.Cu" signal "GND2")
		(14 "In6.Cu" signal "IN3")
		(16 "In7.Cu" signal "GND3")
		(18 "In8.Cu" signal "VCC")
		(20 "In9.Cu" signal "VCC1")
		(22 "In10.Cu" signal "GND4")
		(24 "In11.Cu" signal "IN4")
		(26 "In12.Cu" signal "GND5")
		(28 "In13.Cu" signal "IN5")
		(30 "In14.Cu" signal "GND6")
		(32 "In15.Cu" signal "IN6")
		(34 "In16.Cu" signal "GND7")
		(2 "B.Cu" signal "BOTTOM")
		(9 "F.Adhes" user "F.Adhesive")
		(11 "B.Adhes" user "B.Adhesive")
		(13 "F.Paste" user "Package Geometry/Pastemask Top")
		(15 "B.Paste" user "Package Geometry/Pastemask Bottom")
		(5 "F.SilkS" user "Ref Des/Silkscreen Top")
		(7 "B.SilkS" user "Ref Des/Silkscreen Bottom")
		(1 "F.Mask" user "Board Geometry/Soldermask Top")
		(3 "B.Mask" user "Board Geometry/Soldermask Bottom")
		(17 "Dwgs.User" user "User.Drawings")
		(19 "Cmts.User" user "User.Comments")
		(21 "Eco1.User" user "User.Eco1")
		(23 "Eco2.User" user "User.Eco2")
		(25 "Edge.Cuts" user "Board Geometry/Outline")
		(27 "Margin" user)
		(31 "F.CrtYd" user "Package Geometry/Place Bound Top")
		(29 "B.CrtYd" user "Package Geometry/Place Bound Bottom")
		(35 "F.Fab" user "Ref Des/Assembly Top")
		(33 "B.Fab" user "Ref Des/Assembly Bottom")
	)
	(footprint ""
		(layer "F.Cu")
		(at 4.747514 -44.106592 90)
		(property "Reference" "R932"
			(at 0 0 90)
			(layer "F.SilkS")
			(hide yes)
			(effects
				(font
					(size 1.27 1.27)
				)
			)
		)
		(property "Value" ""
			(at 0 0 90)
			(layer "F.Fab")
			(effects
				(font
					(size 1.27 1.27)
				)
			)
		)
		(duplicate_pad_numbers_are_jumpers no)
		(fp_line
			(start 0.7874 -0.4064)
			(end 0.7874 0.4064)
			(stroke
				(width 0.1524)
				(type default)
			)
			(layer "F.SilkS")
		)
		(fp_line
			(start -0.7874 -0.4064)
			(end 0.7874 -0.4064)
			(stroke
				(width 0.1524)
				(type default)
			)
			(layer "F.SilkS")
		)
		(fp_line
			(start 0.7874 0.4064)
			(end -0.7874 0.4064)
			(stroke
				(width 0.1524)
				(type default)
			)
			(layer "F.SilkS")
		)
		(fp_line
			(start -0.7874 0.4064)
			(end -0.7874 -0.4064)
			(stroke
				(width 0.1524)
				(type default)
			)
			(layer "F.SilkS")
		)
		(fp_line
			(start -0.12065 -0.305054)
			(end -0.12065 -0.2794)
			(stroke
				(width 0.1)
				(type default)
			)
			(layer "F.Fab")
		)
		(fp_line
			(start -0.67945 -0.305054)
			(end -0.12065 -0.305054)
			(stroke
				(width 0.1)
				(type default)
			)
			(layer "F.Fab")
		)
		(fp_line
			(start 0.67945 -0.3048)
			(end 0.67945 0.3048)
			(stroke
				(width 0.1)
				(type default)
			)
			(layer "F.Fab")
		)
		(fp_line
			(start 0.12065 -0.3048)
			(end 0.67945 -0.3048)
			(stroke
				(width 0.1)
				(type default)
			)
			(layer "F.Fab")
		)
		(fp_line
			(start 0.12065 -0.2794)
			(end 0.12065 -0.3048)
			(stroke
				(width 0.1)
				(type default)
			)
			(layer "F.Fab")
		)
		(fp_line
			(start -0.12065 -0.2794)
			(end 0.12065 -0.2794)
			(stroke
				(width 0.1)
				(type default)
			)
			(layer "F.Fab")
		)
		(fp_line
			(start 0.120396 0.2794)
			(end -0.12065 0.2794)
			(stroke
				(width 0.1)
				(type default)
			)
			(layer "F.Fab")
		)
		(fp_line
			(start -0.12065 0.2794)
			(end -0.12065 0.3048)
			(stroke
				(width 0.1)
				(type default)
			)
			(layer "F.Fab")
		)
		(fp_line
			(start 0.67945 0.3048)
			(end 0.120396 0.3048)
			(stroke
				(width 0.1)
				(type default)
			)
			(layer "F.Fab")
		)
		(fp_line
			(start 0.120396 0.3048)
			(end 0.120396 0.2794)
			(stroke
				(width 0.1)
				(type default)
			)
			(layer "F.Fab")
		)
		(fp_line
			(start -0.12065 0.3048)
			(end -0.67945 0.3048)
			(stroke
				(width 0.1)
				(type default)
			)
			(layer "F.Fab")
		)
		(fp_line
			(start -0.67945 0.3048)
			(end -0.67945 -0.305054)
			(stroke
				(width 0.1)
				(type default)
			)
			(layer "F.Fab")
		)
		(pad "1" smd circle
			(at -0.40005 0 90)
			(size 0 0)
			(layers "F.Cu" "F.Mask" "F.Paste")
			(net "CPU1_XTRIG_L7")
		)
		(pad "2" smd circle
			(at 0.40005 0 90)
			(size 0 0)
			(layers "F.Cu" "F.Mask" "F.Paste")
			(net "CPU1_XTRIG_R1_L7")
		)
	)
	(footprint ""
		(layer "F.Cu")
		(at 117.895624 -260.305296 180)
		(property "Reference" "C2286"
			(at 0 0 180)
			(layer "F.SilkS")
			(hide yes)
			(effects
				(font
					(size 1.27 1.27)
				)
			)
		)
		(property "Value" ""
			(at 0 0 180)
			(layer "F.Fab")
			(effects
				(font
					(size 1.27 1.27)
				)
			)
		)
		(duplicate_pad_numbers_are_jumpers no)
		(fp_line
			(start 0.7874 0.4064)
			(end -0.7874 0.4064)
			(stroke
				(width 0.1524)
				(type default)
			)
			(layer "F.SilkS")
		)
		(fp_line
			(start 0.7874 -0.4064)
			(end 0.7874 0.4064)
			(stroke
				(width 0.1524)
				(type default)
			)
			(layer "F.SilkS")
		)
		(fp_line
			(start -0.7874 0.4064)
			(end -0.7874 -0.4064)
			(stroke
				(width 0.1524)
				(type default)
			)
			(layer "F.SilkS")
		)
		(fp_line
			(start -0.7874 -0.4064)
			(end 0.7874 -0.4064)
			(stroke
				(width 0.1524)
				(type default)
			)
			(layer "F.SilkS")
		)
		(fp_line
			(start 0.67945 0.3048)
			(end 0.120396 0.3048)
			(stroke
				(width 0.1)
				(type default)
			)
			(layer "F.Fab")
		)
		(fp_line
			(start 0.67945 -0.3048)
			(end 0.67945 0.3048)
			(stroke
				(width 0.1)
				(type default)
			)
			(layer "F.Fab")
		)
		(fp_line
			(start 0.12065 -0.2794)
			(end 0.12065 -0.3048)
			(stroke
				(width 0.1)
				(type default)
			)
			(layer "F.Fab")
		)
		(fp_line
			(start 0.12065 -0.3048)
			(end 0.67945 -0.3048)
			(stroke
				(width 0.1)
				(type default)
			)
			(layer "F.Fab")
		)
		(fp_line
			(start 0.120396 0.3048)
			(end 0.120396 0.2794)
			(stroke
				(width 0.1)
				(type default)
			)
			(layer "F.Fab")
		)
		(fp_line
			(start 0.120396 0.2794)
			(end -0.12065 0.2794)
			(stroke
				(width 0.1)
				(type default)
			)
			(layer "F.Fab")
		)
		(fp_line
			(start -0.12065 0.3048)
			(end -0.67945 0.3048)
			(stroke
				(width 0.1)
				(type default)
			)
			(layer "F.Fab")
		)
		(fp_line
			(start -0.12065 0.2794)
			(end -0.12065 0.3048)
			(stroke
				(width 0.1)
				(type default)
			)
			(layer "F.Fab")
		)
		(fp_line
			(start -0.12065 -0.2794)
			(end 0.12065 -0.2794)
			(stroke
				(width 0.1)
				(type default)
			)
			(layer "F.Fab")
		)
		(fp_line
			(start -0.12065 -0.305054)
			(end -0.12065 -0.2794)
			(stroke
				(width 0.1)
				(type default)
			)
			(layer "F.Fab")
		)
		(fp_line
			(start -0.67945 0.3048)
			(end -0.67945 -0.305054)
			(stroke
				(width 0.1)
				(type default)
			)
			(layer "F.Fab")
		)
		(fp_line
			(start -0.67945 -0.305054)
			(end -0.12065 -0.305054)
			(stroke
				(width 0.1)
				(type default)
			)
			(layer "F.Fab")
		)
		(pad "1" smd circle
			(at -0.40005 0 180)
			(size 0 0)
			(layers "F.Cu" "F.Mask" "F.Paste")
			(net "PVDDCR_SOC_P1")
		)
		(pad "2" smd circle
			(at 0.40005 0 180)
			(size 0 0)
			(layers "F.Cu" "F.Mask" "F.Paste")
			(net "GND")
		)
	)
	(footprint ""
		(layer "F.Cu")
		(at 245.589298 -242.048538)
		(property "Reference" "ME11"
			(at 0 0 0)
			(layer "F.SilkS")
			(hide yes)
			(effects
				(font
					(size 1.27 1.27)
				)
			)
		)
		(property "Value" ""
			(at 0 0 0)
			(layer "F.Fab")
			(effects
				(font
					(size 1.27 1.27)
				)
			)
		)
		(duplicate_pad_numbers_are_jumpers no)
		(zone
			(layer "F.Cu")
			(hatch none 0.5)
			(connect_pads
				(clearance 0)
			)
			(min_thickness 0.25)
			(keepout
				(tracks allowed)
				(vias allowed)
				(pads allowed)
				(copperpour allowed)
				(footprints not_allowed)
			)
			(placement
				(enabled no)
				(sheetname "")
			)
			(fill
				(thermal_gap 0.5)
				(thermal_bridge_width 0.5)
				(island_removal_mode 0)
			)
			(polygon
				(pts
					(arc
						(start 255.589278 -242.048538)
						(mid 235.589318 -242.048538)
						(end 255.589278 -242.048538)
					)
				)
			)
		)
	)
)
